(kicad_pcb
	(version 20260206)
	(generator "pcbnew")
	(generator_version "10.0")
	(general
		(thickness 1.6)
		(legacy_teardrops no)
	)
	(paper "A4")
	(title_block
		(title "04192023_DAF0TMB3IC0_F0TG_MB_C_brd_V02_OCP.brd")
		(comment 1 "Grand Teton / footprint 2449 of 8354 (J23), pads 227-291 of 291")
	)
	(layers
		(0 "F.Cu" signal "TOP")
		(4 "In1.Cu" signal "GND")
		(6 "In2.Cu" signal "IN1")
		(8 "In3.Cu" signal "GND1")
		(10 "In4.Cu" signal "IN2")
		(12 "In5.Cu" signal "GND2")
		(14 "In6.Cu" signal "IN3")
		(16 "In7.Cu" signal "GND3")
		(18 "In8.Cu" signal "VCC")
		(20 "In9.Cu" signal "VCC1")
		(22 "In10.Cu" signal "GND4")
		(24 "In11.Cu" signal "IN4")
		(26 "In12.Cu" signal "GND5")
		(28 "In13.Cu" signal "IN5")
		(30 "In14.Cu" signal "GND6")
		(32 "In15.Cu" signal "IN6")
		(34 "In16.Cu" signal "GND7")
		(2 "B.Cu" signal "BOTTOM")
		(9 "F.Adhes" user "F.Adhesive")
		(11 "B.Adhes" user "B.Adhesive")
		(13 "F.Paste" user "Package Geometry/Pastemask Top")
		(15 "B.Paste" user "Package Geometry/Pastemask Bottom")
		(5 "F.SilkS" user "Ref Des/Silkscreen Top")
		(7 "B.SilkS" user "Ref Des/Silkscreen Bottom")
		(1 "F.Mask" user "Board Geometry/Soldermask Top")
		(3 "B.Mask" user "Board Geometry/Soldermask Bottom")
		(17 "Dwgs.User" user "User.Drawings")
		(19 "Cmts.User" user "User.Comments")
		(21 "Eco1.User" user "User.Eco1")
		(23 "Eco2.User" user "User.Eco2")
		(25 "Edge.Cuts" user "Board Geometry/Outline")
		(27 "Margin" user)
		(31 "F.CrtYd" user "Package Geometry/Place Bound Top")
		(29 "B.CrtYd" user "Package Geometry/Place Bound Bottom")
		(35 "F.Fab" user "Ref Des/Assembly Top")
		(33 "B.Fab" user "Ref Des/Assembly Bottom")
	)
	(footprint ""
		(layer "F.Cu")
		(at 267.598144 -255.560068 180)
		(property "Reference" "J23"
			(at -2.2098 -81.984088 0)
			(unlocked yes)
			(layer "F.SilkS")
			(effects
				(font
					(size 0.7874 0.5842)
					(thickness 0.1524)
				)
			)
		)
		(property "Value" ""
			(at 0 0 180)
			(layer "F.Fab")
			(effects
				(font
					(size 1.27 1.27)
				)
			)
		)
		(duplicate_pad_numbers_are_jumpers no)
		(pad "227" smd rect
			(at 2.050034 11.474958 90)
			(size 0.519938 1.4986)
			(layers "F.Cu" "F.Mask" "F.Paste")
			(net "M_F_CPU0_SB_PAR")
		)
		(pad "228" smd rect
			(at 2.050034 12.325096 90)
			(size 0.519938 1.4986)
			(layers "F.Cu" "F.Mask" "F.Paste")
			(net "GND")
		)
		(pad "229" smd rect
			(at 2.050034 13.17498 90)
			(size 0.519938 1.4986)
			(layers "F.Cu" "F.Mask" "F.Paste")
			(net "M_F_CPU0_SB_CS_N<1>")
		)
		(pad "230" smd rect
			(at 2.050034 14.025118 90)
			(size 0.519938 1.4986)
			(layers "F.Cu" "F.Mask" "F.Paste")
			(net "GND")
		)
		(pad "231" smd rect
			(at 2.050034 14.875002 90)
			(size 0.519938 1.4986)
			(layers "F.Cu" "F.Mask" "F.Paste")
			(net "Net_2324")
		)
		(pad "232" smd rect
			(at 2.050034 15.724886 90)
			(size 0.519938 1.4986)
			(layers "F.Cu" "F.Mask" "F.Paste")
			(net "Net_2325")
		)
		(pad "233" smd rect
			(at 2.050034 16.575024 90)
			(size 0.519938 1.4986)
			(layers "F.Cu" "F.Mask" "F.Paste")
			(net "GND")
		)
		(pad "234" smd rect
			(at 2.050034 17.424908 90)
			(size 0.519938 1.4986)
			(layers "F.Cu" "F.Mask" "F.Paste")
			(net "M_F_CPU0_SB_CB<6>")
		)
		(pad "235" smd rect
			(at 2.050034 18.275046 90)
			(size 0.519938 1.4986)
			(layers "F.Cu" "F.Mask" "F.Paste")
			(net "GND")
		)
		(pad "236" smd rect
			(at 2.050034 19.12493 90)
			(size 0.519938 1.4986)
			(layers "F.Cu" "F.Mask" "F.Paste")
			(net "M_F_CPU0_SB_CB<7>")
		)
		(pad "237" smd rect
			(at 2.050034 19.975068 90)
			(size 0.519938 1.4986)
			(layers "F.Cu" "F.Mask" "F.Paste")
			(net "GND")
		)
		(pad "238" smd rect
			(at 2.050034 20.824952 90)
			(size 0.519938 1.4986)
			(layers "F.Cu" "F.Mask" "F.Paste")
			(net "M_F_CPU0_SB_DQS_DN<4>")
		)
		(pad "239" smd rect
			(at 2.050034 21.67509 90)
			(size 0.519938 1.4986)
			(layers "F.Cu" "F.Mask" "F.Paste")
			(net "M_F_CPU0_SB_DQS_DP<4>")
		)
		(pad "240" smd rect
			(at 2.050034 22.524974 90)
			(size 0.519938 1.4986)
			(layers "F.Cu" "F.Mask" "F.Paste")
			(net "GND")
		)
		(pad "241" smd rect
			(at 2.050034 23.375112 90)
			(size 0.519938 1.4986)
			(layers "F.Cu" "F.Mask" "F.Paste")
			(net "M_F_CPU0_SB_CB<2>")
		)
		(pad "242" smd rect
			(at 2.050034 24.224996 90)
			(size 0.519938 1.4986)
			(layers "F.Cu" "F.Mask" "F.Paste")
			(net "GND")
		)
		(pad "243" smd rect
			(at 2.050034 25.07488 90)
			(size 0.519938 1.4986)
			(layers "F.Cu" "F.Mask" "F.Paste")
			(net "M_F_CPU0_SB_CB<3>")
		)
		(pad "244" smd rect
			(at 2.050034 25.925018 90)
			(size 0.519938 1.4986)
			(layers "F.Cu" "F.Mask" "F.Paste")
			(net "GND")
		)
		(pad "245" smd rect
			(at 2.050034 26.774902 90)
			(size 0.519938 1.4986)
			(layers "F.Cu" "F.Mask" "F.Paste")
			(net "M_F_CPU0_SB_DQ<2>")
		)
		(pad "246" smd rect
			(at 2.050034 27.62504 90)
			(size 0.519938 1.4986)
			(layers "F.Cu" "F.Mask" "F.Paste")
			(net "GND")
		)
		(pad "247" smd rect
			(at 2.050034 28.474924 90)
			(size 0.519938 1.4986)
			(layers "F.Cu" "F.Mask" "F.Paste")
			(net "M_F_CPU0_SB_DQ<3>")
		)
		(pad "248" smd rect
			(at 2.050034 29.325062 90)
			(size 0.519938 1.4986)
			(layers "F.Cu" "F.Mask" "F.Paste")
			(net "GND")
		)
		(pad "249" smd rect
			(at 2.050034 30.174946 90)
			(size 0.519938 1.4986)
			(layers "F.Cu" "F.Mask" "F.Paste")
			(net "M_F_CPU0_SB_DQS_DN<5>")
		)
		(pad "250" smd rect
			(at 2.050034 31.025084 90)
			(size 0.519938 1.4986)
			(layers "F.Cu" "F.Mask" "F.Paste")
			(net "M_F_CPU0_SB_DQS_DP<5>")
		)
		(pad "251" smd rect
			(at 2.050034 31.874968 90)
			(size 0.519938 1.4986)
			(layers "F.Cu" "F.Mask" "F.Paste")
			(net "GND")
		)
		(pad "252" smd rect
			(at 2.050034 32.725106 90)
			(size 0.519938 1.4986)
			(layers "F.Cu" "F.Mask" "F.Paste")
			(net "M_F_CPU0_SB_DQ<6>")
		)
		(pad "253" smd rect
			(at 2.050034 33.57499 90)
			(size 0.519938 1.4986)
			(layers "F.Cu" "F.Mask" "F.Paste")
			(net "GND")
		)
		(pad "254" smd rect
			(at 2.050034 34.425128 90)
			(size 0.519938 1.4986)
			(layers "F.Cu" "F.Mask" "F.Paste")
			(net "M_F_CPU0_SB_DQ<7>")
		)
		(pad "255" smd rect
			(at 2.050034 35.275012 90)
			(size 0.519938 1.4986)
			(layers "F.Cu" "F.Mask" "F.Paste")
			(net "GND")
		)
		(pad "256" smd rect
			(at 2.050034 36.124896 90)
			(size 0.519938 1.4986)
			(layers "F.Cu" "F.Mask" "F.Paste")
			(net "M_F_CPU0_SB_DQ<10>")
		)
		(pad "257" smd rect
			(at 2.050034 36.975034 90)
			(size 0.519938 1.4986)
			(layers "F.Cu" "F.Mask" "F.Paste")
			(net "GND")
		)
		(pad "258" smd rect
			(at 2.050034 37.824918 90)
			(size 0.519938 1.4986)
			(layers "F.Cu" "F.Mask" "F.Paste")
			(net "M_F_CPU0_SB_DQ<11>")
		)
		(pad "259" smd rect
			(at 2.050034 38.675056 90)
			(size 0.519938 1.4986)
			(layers "F.Cu" "F.Mask" "F.Paste")
			(net "GND")
		)
		(pad "260" smd rect
			(at 2.050034 39.52494 90)
			(size 0.519938 1.4986)
			(layers "F.Cu" "F.Mask" "F.Paste")
			(net "M_F_CPU0_SB_DQS_DN<6>")
		)
		(pad "261" smd rect
			(at 2.050034 40.375078 90)
			(size 0.519938 1.4986)
			(layers "F.Cu" "F.Mask" "F.Paste")
			(net "M_F_CPU0_SB_DQS_DP<6>")
		)
		(pad "262" smd rect
			(at 2.050034 41.224962 90)
			(size 0.519938 1.4986)
			(layers "F.Cu" "F.Mask" "F.Paste")
			(net "GND")
		)
		(pad "263" smd rect
			(at 2.050034 42.0751 90)
			(size 0.519938 1.4986)
			(layers "F.Cu" "F.Mask" "F.Paste")
			(net "M_F_CPU0_SB_DQ<14>")
		)
		(pad "264" smd rect
			(at 2.050034 42.924984 90)
			(size 0.519938 1.4986)
			(layers "F.Cu" "F.Mask" "F.Paste")
			(net "GND")
		)
		(pad "265" smd rect
			(at 2.050034 43.775122 90)
			(size 0.519938 1.4986)
			(layers "F.Cu" "F.Mask" "F.Paste")
			(net "M_F_CPU0_SB_DQ<15>")
		)
		(pad "266" smd rect
			(at 2.050034 44.625006 90)
			(size 0.519938 1.4986)
			(layers "F.Cu" "F.Mask" "F.Paste")
			(net "GND")
		)
		(pad "267" smd rect
			(at 2.050034 45.47489 90)
			(size 0.519938 1.4986)
			(layers "F.Cu" "F.Mask" "F.Paste")
			(net "M_F_CPU0_SB_DQ<18>")
		)
		(pad "268" smd rect
			(at 2.050034 46.325028 90)
			(size 0.519938 1.4986)
			(layers "F.Cu" "F.Mask" "F.Paste")
			(net "GND")
		)
		(pad "269" smd rect
			(at 2.050034 47.174912 90)
			(size 0.519938 1.4986)
			(layers "F.Cu" "F.Mask" "F.Paste")
			(net "M_F_CPU0_SB_DQ<19>")
		)
		(pad "270" smd rect
			(at 2.050034 48.02505 90)
			(size 0.519938 1.4986)
			(layers "F.Cu" "F.Mask" "F.Paste")
			(net "GND")
		)
		(pad "271" smd rect
			(at 2.050034 48.874934 90)
			(size 0.519938 1.4986)
			(layers "F.Cu" "F.Mask" "F.Paste")
			(net "M_F_CPU0_SB_DQS_DN<7>")
		)
		(pad "272" smd rect
			(at 2.050034 49.725072 90)
			(size 0.519938 1.4986)
			(layers "F.Cu" "F.Mask" "F.Paste")
			(net "M_F_CPU0_SB_DQS_DP<7>")
		)
		(pad "273" smd rect
			(at 2.050034 50.574956 90)
			(size 0.519938 1.4986)
			(layers "F.Cu" "F.Mask" "F.Paste")
			(net "GND")
		)
		(pad "274" smd rect
			(at 2.050034 51.425094 90)
			(size 0.519938 1.4986)
			(layers "F.Cu" "F.Mask" "F.Paste")
			(net "M_F_CPU0_SB_DQ<22>")
		)
		(pad "275" smd rect
			(at 2.050034 52.274978 90)
			(size 0.519938 1.4986)
			(layers "F.Cu" "F.Mask" "F.Paste")
			(net "GND")
		)
		(pad "276" smd rect
			(at 2.050034 53.125116 90)
			(size 0.519938 1.4986)
			(layers "F.Cu" "F.Mask" "F.Paste")
			(net "M_F_CPU0_SB_DQ<23>")
		)
		(pad "277" smd rect
			(at 2.050034 53.975 90)
			(size 0.519938 1.4986)
			(layers "F.Cu" "F.Mask" "F.Paste")
			(net "GND")
		)
		(pad "278" smd rect
			(at 2.050034 54.824884 90)
			(size 0.519938 1.4986)
			(layers "F.Cu" "F.Mask" "F.Paste")
			(net "M_F_CPU0_SB_DQ<26>")
		)
		(pad "279" smd rect
			(at 2.050034 55.675022 90)
			(size 0.519938 1.4986)
			(layers "F.Cu" "F.Mask" "F.Paste")
			(net "GND")
		)
		(pad "280" smd rect
			(at 2.050034 56.524906 90)
			(size 0.519938 1.4986)
			(layers "F.Cu" "F.Mask" "F.Paste")
			(net "M_F_CPU0_SB_DQ<27>")
		)
		(pad "281" smd rect
			(at 2.050034 57.375044 90)
			(size 0.519938 1.4986)
			(layers "F.Cu" "F.Mask" "F.Paste")
			(net "GND")
		)
		(pad "282" smd rect
			(at 2.050034 58.224928 90)
			(size 0.519938 1.4986)
			(layers "F.Cu" "F.Mask" "F.Paste")
			(net "M_F_CPU0_SB_DQS_DN<8>")
		)
		(pad "283" smd rect
			(at 2.050034 59.075066 90)
			(size 0.519938 1.4986)
			(layers "F.Cu" "F.Mask" "F.Paste")
			(net "M_F_CPU0_SB_DQS_DP<8>")
		)
		(pad "284" smd rect
			(at 2.050034 59.92495 90)
			(size 0.519938 1.4986)
			(layers "F.Cu" "F.Mask" "F.Paste")
			(net "GND")
		)
		(pad "285" smd rect
			(at 2.050034 60.775088 90)
			(size 0.519938 1.4986)
			(layers "F.Cu" "F.Mask" "F.Paste")
			(net "M_F_CPU0_SB_DQ<30>")
		)
		(pad "286" smd rect
			(at 2.050034 61.624972 90)
			(size 0.519938 1.4986)
			(layers "F.Cu" "F.Mask" "F.Paste")
			(net "GND")
		)
		(pad "287" smd rect
			(at 2.050034 62.47511 90)
			(size 0.519938 1.4986)
			(layers "F.Cu" "F.Mask" "F.Paste")
			(net "M_F_CPU0_SB_DQ<31>")
		)
		(pad "288" smd rect
			(at 2.050034 63.324994 90)
			(size 0.519938 1.4986)
			(layers "F.Cu" "F.Mask" "F.Paste")
			(net "GND")
		)
		(pad "G1" thru_hole oval
			(at 0 -68.97497 90)
			(size 1.7272 3.4798)
			(drill oval 1.2192 2.4638)
			(layers "*.Cu" "*.Mask")
			(remove_unused_layers no)
			(net "GND")
			(clearance 0.127)
			(thermal_gap 0.127)
		)
		(pad "G2" thru_hole oval
			(at 0 3.875024 90)
			(size 1.7272 3.4798)
			(drill oval 1.2192 2.4638)
			(layers "*.Cu" "*.Mask")
			(remove_unused_layers no)
			(net "GND")
			(clearance 0.127)
			(thermal_gap 0.127)
		)
		(pad "G3" thru_hole oval
			(at 0 68.97497 90)
			(size 1.7272 3.4798)
			(drill oval 1.2192 2.4638)
			(layers "*.Cu" "*.Mask")
			(remove_unused_layers no)
			(net "GND")
			(clearance 0.127)
			(thermal_gap 0.127)
		)
	)
)
